(kicad_pcb
	(version 20260206)
	(generator "pcbnew")
	(generator_version "10.0")
	(general
		(thickness 1.6)
		(legacy_teardrops no)
	)
	(paper "A4")
	(title_block
		(title "timecard-production-celestica-r4006 — R4006-B0001-02_R01.brd")
		(comment 1 "Time Appliance Project (Time Card) / footprints 857-861 of 1113")
	)
	(layers
		(0 "F.Cu" signal "TOP")
		(4 "In1.Cu" signal "L02_GND1")
		(6 "In2.Cu" signal "L03_SIG1")
		(8 "In3.Cu" signal "L04_GND2")
		(10 "In4.Cu" signal "L05_VCC1")
		(12 "In5.Cu" signal "L06_VCC2")
		(14 "In6.Cu" signal "L07_GND3")
		(16 "In7.Cu" signal "L08_SIG2")
		(18 "In8.Cu" signal "L09_GND4")
		(2 "B.Cu" signal "BOTTOM")
		(9 "F.Adhes" user "F.Adhesive")
		(11 "B.Adhes" user "B.Adhesive")
		(13 "F.Paste" user "Package Geometry/Pastemask Top")
		(15 "B.Paste" user "Package Geometry/Pastemask Bottom")
		(5 "F.SilkS" user "Ref Des/Silkscreen Top")
		(7 "B.SilkS" user "Ref Des/Silkscreen Bottom")
		(1 "F.Mask" user "Board Geometry/Soldermask Top")
		(3 "B.Mask" user "Board Geometry/Soldermask Bottom")
		(17 "Dwgs.User" user "User.Drawings")
		(19 "Cmts.User" user "User.Comments")
		(21 "Eco1.User" user "User.Eco1")
		(23 "Eco2.User" user "User.Eco2")
		(25 "Edge.Cuts" user "Board Geometry/Outline")
		(27 "Margin" user)
		(31 "F.CrtYd" user "Package Geometry/Place Bound Top")
		(29 "B.CrtYd" user "Package Geometry/Place Bound Bottom")
		(35 "F.Fab" user "Ref Des/Assembly Top")
		(33 "B.Fab" user "Ref Des/Assembly Bottom")
	)
	(footprint ""
		(layer "B.Cu")
		(at 104.347264 -39.823136 180)
		(property "Reference" "C118"
			(at 41.400984 -1.251966 0)
			(unlocked yes)
			(layer "B.SilkS")
			(effects
				(font
					(size 0.635 0.4064)
					(thickness 0.1524)
				)
				(justify mirror)
			)
		)
		(property "Value" "VAL*"
			(at 0 3.718306 180)
			(unlocked yes)
			(layer "B.Fab")
			(hide yes)
			(effects
				(font
					(size 0.7874 0.5842)
					(thickness 0.127)
				)
				(justify mirror)
			)
		)
		(property "Tolerance" "TOL*"
			(at 0 4.861306 180)
			(unlocked yes)
			(layer "Cmts.User")
			(hide yes)
			(effects
				(font
					(size 0.7874 0.5842)
					(thickness 0.127)
				)
				(justify mirror)
			)
		)
		(property "User Part Number" "PARTNUM*"
			(at 0 2.575306 180)
			(unlocked yes)
			(layer "Cmts.User")
			(hide yes)
			(effects
				(font
					(size 0.7874 0.5842)
					(thickness 0.127)
				)
				(justify mirror)
			)
		)
		(property "Device Type" "CAPACITOR-G105-0B104-CK,0.1UF,A"
			(at 0 1.432306 180)
			(unlocked yes)
			(layer "B.Fab")
			(hide yes)
			(effects
				(font
					(size 0.7874 0.5842)
					(thickness 0.127)
				)
				(justify mirror)
			)
		)
		(duplicate_pad_numbers_are_jumpers no)
		(fp_line
			(start 0.970026 0.4699)
			(end 0.970026 -0.4699)
			(stroke
				(width 0.1)
				(type default)
			)
			(layer "B.SilkS")
		)
		(fp_line
			(start 0.970026 -0.4699)
			(end -0.970026 -0.4699)
			(stroke
				(width 0.1)
				(type default)
			)
			(layer "B.SilkS")
		)
		(fp_line
			(start -0.970026 0.4699)
			(end 0.970026 0.4699)
			(stroke
				(width 0.1)
				(type default)
			)
			(layer "B.SilkS")
		)
		(fp_line
			(start -0.970026 -0.4699)
			(end -0.970026 0.4699)
			(stroke
				(width 0.1)
				(type default)
			)
			(layer "B.SilkS")
		)
		(fp_poly
			(pts
				(xy 0.970026 0.4699) (xy -0.970026 0.4699) (xy -0.970026 -0.4699) (xy 0.970026 -0.4699)
			)
			(stroke
				(width 0)
				(type default)
			)
			(fill no)
			(layer "B.CrtYd")
		)
		(fp_line
			(start 0.508 0.3048)
			(end 0.508 -0.3048)
			(stroke
				(width 0.1)
				(type default)
			)
			(layer "B.Fab")
		)
		(fp_line
			(start 0.508 -0.3048)
			(end -0.508 -0.3048)
			(stroke
				(width 0.1)
				(type default)
			)
			(layer "B.Fab")
		)
		(fp_line
			(start -0.508 0.3048)
			(end 0.508 0.3048)
			(stroke
				(width 0.1)
				(type default)
			)
			(layer "B.Fab")
		)
		(fp_line
			(start -0.508 -0.3048)
			(end -0.508 0.3048)
			(stroke
				(width 0.1)
				(type default)
			)
			(layer "B.Fab")
		)
		(pad "1" smd circle
			(at 0.500126 0)
			(size 0.635 0.635)
			(layers "B.Cu" "B.Mask" "B.Paste")
			(net "XP1R0V_FPGA_MGTAVCC")
		)
		(pad "2" smd circle
			(at -0.500126 0)
			(size 0.635 0.635)
			(layers "B.Cu" "B.Mask" "B.Paste")
			(net "SG")
		)
	)
	(footprint ""
		(layer "B.Cu")
		(at 71.13397 -15.367 -90)
		(property "Reference" "C28"
			(at 2.286 0.17272 270)
			(unlocked yes)
			(layer "B.SilkS")
			(effects
				(font
					(size 0.635 0.4064)
					(thickness 0.1524)
				)
				(justify mirror)
			)
		)
		(property "Value" "VAL*"
			(at -0.0762 2.067306 270)
			(unlocked yes)
			(layer "B.Fab")
			(hide yes)
			(effects
				(font
					(size 0.7874 0.5842)
					(thickness 0.1524)
				)
				(justify mirror)
			)
		)
		(property "Tolerance" "TOL*"
			(at -0.0762 3.032506 270)
			(unlocked yes)
			(layer "Cmts.User")
			(hide yes)
			(effects
				(font
					(size 0.7874 0.5842)
					(thickness 0.1524)
				)
				(justify mirror)
			)
		)
		(property "User Part Number" "PARTNUM*"
			(at -0.1016 4.023106 270)
			(unlocked yes)
			(layer "Cmts.User")
			(hide yes)
			(effects
				(font
					(size 0.7874 0.5842)
					(thickness 0.1524)
				)
				(justify mirror)
			)
		)
		(property "Device Type" "CAPACITOR-G105-0B104-CK,0.1UF,A"
			(at -0.0508 1.127506 270)
			(unlocked yes)
			(layer "B.Fab")
			(hide yes)
			(effects
				(font
					(size 0.7874 0.5842)
					(thickness 0.1524)
				)
				(justify mirror)
			)
		)
		(duplicate_pad_numbers_are_jumpers no)
		(fp_line
			(start -1.143 0.5588)
			(end -1.143 -0.5588)
			(stroke
				(width 0.1)
				(type default)
			)
			(layer "B.SilkS")
		)
		(fp_line
			(start 1.143 0.5588)
			(end -1.143 0.5588)
			(stroke
				(width 0.1)
				(type default)
			)
			(layer "B.SilkS")
		)
		(fp_line
			(start -1.143 -0.5588)
			(end 1.143 -0.5588)
			(stroke
				(width 0.1)
				(type default)
			)
			(layer "B.SilkS")
		)
		(fp_line
			(start 1.143 -0.5588)
			(end 1.143 0.5588)
			(stroke
				(width 0.1)
				(type default)
			)
			(layer "B.SilkS")
		)
		(fp_rect
			(start 1.143 0.5588)
			(end -1.143 -0.5588)
			(stroke
				(width 0)
				(type default)
			)
			(fill no)
			(layer "B.CrtYd")
		)
		(fp_line
			(start -0.508 0.3048)
			(end -0.508 -0.3048)
			(stroke
				(width 0.1)
				(type default)
			)
			(layer "B.Fab")
		)
		(fp_line
			(start 0.508 0.3048)
			(end -0.508 0.3048)
			(stroke
				(width 0.1)
				(type default)
			)
			(layer "B.Fab")
		)
		(fp_line
			(start -0.508 -0.3048)
			(end 0.508 -0.3048)
			(stroke
				(width 0.1)
				(type default)
			)
			(layer "B.Fab")
		)
		(fp_line
			(start 0.508 -0.3048)
			(end 0.508 0.3048)
			(stroke
				(width 0.1)
				(type default)
			)
			(layer "B.Fab")
		)
		(pad "1" smd rect
			(at 0.5334 0 90)
			(size 0.7112 0.6096)
			(layers "B.Cu" "B.Mask" "B.Paste")
			(net "C_CPU_RX_PCIE_MGT2_TXP")
		)
		(pad "2" smd rect
			(at -0.5334 0 90)
			(size 0.7112 0.6096)
			(layers "B.Cu" "B.Mask" "B.Paste")
			(net "CPU_RX_PCIE_MGT2_TXP")
		)
		(zone
			(layer "B.Cu")
			(hatch none 0.5)
			(connect_pads
				(clearance 0)
			)
			(min_thickness 0.25)
			(keepout
				(tracks allowed)
				(vias not_allowed)
				(pads allowed)
				(copperpour not_allowed)
				(footprints allowed)
			)
			(placement
				(enabled no)
				(sheetname "")
			)
			(fill
				(thermal_gap 0.5)
				(thermal_bridge_width 0.5)
				(island_removal_mode 0)
			)
			(polygon
				(pts
					(xy 70.82917 -15.2908) (xy 71.43877 -15.2908) (xy 71.43877 -15.4432) (xy 70.82917 -15.4432)
				)
			)
		)
	)
	(footprint ""
		(layer "B.Cu")
		(at 87.376 -73.279 90)
		(property "Reference" "R330"
			(at -3.556 -0.16637 270)
			(unlocked yes)
			(layer "B.SilkS")
			(effects
				(font
					(size 0.7874 0.5842)
					(thickness 0.1524)
				)
				(justify mirror)
			)
		)
		(property "Value" "VAL*"
			(at -0.02032 2.13233 90)
			(unlocked yes)
			(layer "B.Fab")
			(hide yes)
			(effects
				(font
					(size 0.7874 0.5842)
					(thickness 0.1524)
				)
				(justify mirror)
			)
		)
		(property "Device Type" "RESISTOR-G155-133R0-01,33OHM,1%"
			(at -0.008382 1.210564 90)
			(unlocked yes)
			(layer "B.Fab")
			(hide yes)
			(effects
				(font
					(size 0.7874 0.5842)
					(thickness 0.1524)
				)
				(justify mirror)
			)
		)
		(property "User Part Number" "PARTNUM*"
			(at -0.02032 4.024884 90)
			(unlocked yes)
			(layer "Cmts.User")
			(hide yes)
			(effects
				(font
					(size 0.7874 0.5842)
					(thickness 0.1524)
				)
				(justify mirror)
			)
		)
		(property "Tolerance" "TOL*"
			(at -0.044704 3.05435 90)
			(unlocked yes)
			(layer "Cmts.User")
			(hide yes)
			(effects
				(font
					(size 0.7874 0.5842)
					(thickness 0.1524)
				)
				(justify mirror)
			)
		)
		(duplicate_pad_numbers_are_jumpers no)
		(fp_line
			(start 1.143 -0.5588)
			(end 1.143 0.5588)
			(stroke
				(width 0.1)
				(type default)
			)
			(layer "B.SilkS")
		)
		(fp_line
			(start -1.143 -0.5588)
			(end 1.143 -0.5588)
			(stroke
				(width 0.1)
				(type default)
			)
			(layer "B.SilkS")
		)
		(fp_line
			(start 1.143 0.5588)
			(end -1.143 0.5588)
			(stroke
				(width 0.1)
				(type default)
			)
			(layer "B.SilkS")
		)
		(fp_line
			(start -1.143 0.5588)
			(end -1.143 -0.5588)
			(stroke
				(width 0.1)
				(type default)
			)
			(layer "B.SilkS")
		)
		(fp_rect
			(start 1.143 -0.5588)
			(end -1.143 0.5588)
			(stroke
				(width 0)
				(type default)
			)
			(fill no)
			(layer "B.CrtYd")
		)
		(fp_line
			(start 0.508 -0.3048)
			(end 0.508 0.3048)
			(stroke
				(width 0.1)
				(type default)
			)
			(layer "B.Fab")
		)
		(fp_line
			(start -0.508 -0.3048)
			(end 0.508 -0.3048)
			(stroke
				(width 0.1)
				(type default)
			)
			(layer "B.Fab")
		)
		(fp_line
			(start 0.508 0.3048)
			(end -0.508 0.3048)
			(stroke
				(width 0.1)
				(type default)
			)
			(layer "B.Fab")
		)
		(fp_line
			(start -0.508 0.3048)
			(end -0.508 -0.3048)
			(stroke
				(width 0.1)
				(type default)
			)
			(layer "B.Fab")
		)
		(pad "1" smd rect
			(at 0.5334 0 270)
			(size 0.7112 0.6096)
			(layers "B.Cu" "B.Mask" "B.Paste")
			(net "R_BNO080_EVN_SDA")
		)
		(pad "2" smd rect
			(at -0.5334 0 270)
			(size 0.7112 0.6096)
			(layers "B.Cu" "B.Mask" "B.Paste")
			(net "BNO080_EVN_SDA")
		)
		(zone
			(layer "B.Cu")
			(hatch none 0.5)
			(connect_pads
				(clearance 0)
			)
			(min_thickness 0.25)
			(keepout
				(tracks allowed)
				(vias not_allowed)
				(pads allowed)
				(copperpour not_allowed)
				(footprints allowed)
			)
			(placement
				(enabled no)
				(sheetname "")
			)
			(fill
				(thermal_gap 0.5)
				(thermal_bridge_width 0.5)
				(island_removal_mode 0)
			)
			(polygon
				(pts
					(xy 87.0712 -73.3552) (xy 87.0712 -73.2028) (xy 87.6808 -73.2028) (xy 87.6808 -73.3552)
				)
			)
		)
	)
	(footprint ""
		(layer "B.Cu")
		(at 114.34699 -52.82311)
		(property "Reference" "C134"
			(at -0.04699 -1.12014 0)
			(unlocked yes)
			(layer "B.SilkS")
			(effects
				(font
					(size 0.635 0.4064)
					(thickness 0.1524)
				)
				(justify mirror)
			)
		)
		(property "Value" "VAL*"
			(at 0 3.718306 0)
			(unlocked yes)
			(layer "B.Fab")
			(hide yes)
			(effects
				(font
					(size 0.7874 0.5842)
					(thickness 0.127)
				)
				(justify mirror)
			)
		)
		(property "Tolerance" "TOL*"
			(at 0 4.861306 0)
			(unlocked yes)
			(layer "Cmts.User")
			(hide yes)
			(effects
				(font
					(size 0.7874 0.5842)
					(thickness 0.127)
				)
				(justify mirror)
			)
		)
		(property "User Part Number" "PARTNUM*"
			(at 0 2.575306 0)
			(unlocked yes)
			(layer "Cmts.User")
			(hide yes)
			(effects
				(font
					(size 0.7874 0.5842)
					(thickness 0.127)
				)
				(justify mirror)
			)
		)
		(property "Device Type" "CAPACITOR-G105-0B104-CK,0.1UF,A"
			(at 0 1.432306 0)
			(unlocked yes)
			(layer "B.Fab")
			(hide yes)
			(effects
				(font
					(size 0.7874 0.5842)
					(thickness 0.127)
				)
				(justify mirror)
			)
		)
		(duplicate_pad_numbers_are_jumpers no)
		(fp_line
			(start -0.970026 -0.4699)
			(end -0.970026 0.4699)
			(stroke
				(width 0.1)
				(type default)
			)
			(layer "B.SilkS")
		)
		(fp_line
			(start -0.970026 0.4699)
			(end 0.970026 0.4699)
			(stroke
				(width 0.1)
				(type default)
			)
			(layer "B.SilkS")
		)
		(fp_line
			(start 0.970026 -0.4699)
			(end -0.970026 -0.4699)
			(stroke
				(width 0.1)
				(type default)
			)
			(layer "B.SilkS")
		)
		(fp_line
			(start 0.970026 0.4699)
			(end 0.970026 -0.4699)
			(stroke
				(width 0.1)
				(type default)
			)
			(layer "B.SilkS")
		)
		(fp_poly
			(pts
				(xy 0.970026 0.4699) (xy -0.970026 0.4699) (xy -0.970026 -0.4699) (xy 0.970026 -0.4699)
			)
			(stroke
				(width 0)
				(type default)
			)
			(fill no)
			(layer "B.CrtYd")
		)
		(fp_line
			(start -0.508 -0.3048)
			(end -0.508 0.3048)
			(stroke
				(width 0.1)
				(type default)
			)
			(layer "B.Fab")
		)
		(fp_line
			(start -0.508 0.3048)
			(end 0.508 0.3048)
			(stroke
				(width 0.1)
				(type default)
			)
			(layer "B.Fab")
		)
		(fp_line
			(start 0.508 -0.3048)
			(end -0.508 -0.3048)
			(stroke
				(width 0.1)
				(type default)
			)
			(layer "B.Fab")
		)
		(fp_line
			(start 0.508 0.3048)
			(end 0.508 -0.3048)
			(stroke
				(width 0.1)
				(type default)
			)
			(layer "B.Fab")
		)
		(pad "1" smd circle
			(at 0.500126 0 180)
			(size 0.635 0.635)
			(layers "B.Cu" "B.Mask" "B.Paste")
			(net "XP3R3V_FPGA")
		)
		(pad "2" smd circle
			(at -0.500126 0 180)
			(size 0.635 0.635)
			(layers "B.Cu" "B.Mask" "B.Paste")
			(net "SG")
		)
	)
	(footprint ""
		(layer "B.Cu")
		(at 151.892 -42.037 90)
		(property "Reference" "R433"
			(at -8.42137 0.635 0)
			(unlocked yes)
			(layer "B.SilkS")
			(effects
				(font
					(size 0.7874 0.5842)
					(thickness 0.1524)
				)
				(justify mirror)
			)
		)
		(property "Value" "VAL*"
			(at -0.02032 2.13233 90)
			(unlocked yes)
			(layer "B.Fab")
			(hide yes)
			(effects
				(font
					(size 0.7874 0.5842)
					(thickness 0.1524)
				)
				(justify mirror)
			)
		)
		(property "Tolerance" "TOL*"
			(at -0.044704 3.05435 90)
			(unlocked yes)
			(layer "Cmts.User")
			(hide yes)
			(effects
				(font
					(size 0.7874 0.5842)
					(thickness 0.1524)
				)
				(justify mirror)
			)
		)
		(property "User Part Number" "PARTNUM*"
			(at -0.02032 4.024884 90)
			(unlocked yes)
			(layer "Cmts.User")
			(hide yes)
			(effects
				(font
					(size 0.7874 0.5842)
					(thickness 0.1524)
				)
				(justify mirror)
			)
		)
		(property "Device Type" "RESISTOR-G155-133R0-01,33OHM,1%"
			(at -0.008382 1.210564 90)
			(unlocked yes)
			(layer "B.Fab")
			(hide yes)
			(effects
				(font
					(size 0.7874 0.5842)
					(thickness 0.1524)
				)
				(justify mirror)
			)
		)
		(duplicate_pad_numbers_are_jumpers no)
		(fp_line
			(start 1.143 -0.5588)
			(end 1.143 0.5588)
			(stroke
				(width 0.1)
				(type default)
			)
			(layer "B.SilkS")
		)
		(fp_line
			(start -1.143 -0.5588)
			(end 1.143 -0.5588)
			(stroke
				(width 0.1)
				(type default)
			)
			(layer "B.SilkS")
		)
		(fp_line
			(start 1.143 0.5588)
			(end -1.143 0.5588)
			(stroke
				(width 0.1)
				(type default)
			)
			(layer "B.SilkS")
		)
		(fp_line
			(start -1.143 0.5588)
			(end -1.143 -0.5588)
			(stroke
				(width 0.1)
				(type default)
			)
			(layer "B.SilkS")
		)
		(fp_poly
			(pts
				(xy 1.143 0.5588) (xy -1.143 0.5588) (xy -1.143 -0.5588) (xy 1.143 -0.5588)
			)
			(stroke
				(width 0)
				(type default)
			)
			(fill no)
			(layer "B.CrtYd")
		)
		(fp_line
			(start 0.508 -0.3048)
			(end 0.508 0.3048)
			(stroke
				(width 0.1)
				(type default)
			)
			(layer "B.Fab")
		)
		(fp_line
			(start -0.508 -0.3048)
			(end 0.508 -0.3048)
			(stroke
				(width 0.1)
				(type default)
			)
			(layer "B.Fab")
		)
		(fp_line
			(start 0.508 0.3048)
			(end -0.508 0.3048)
			(stroke
				(width 0.1)
				(type default)
			)
			(layer "B.Fab")
		)
		(fp_line
			(start -0.508 0.3048)
			(end -0.508 -0.3048)
			(stroke
				(width 0.1)
				(type default)
			)
			(layer "B.Fab")
		)
		(pad "1" smd rect
			(at 0.5334 0 270)
			(size 0.7112 0.6096)
			(layers "B.Cu" "B.Mask" "B.Paste")
			(net "UNNAMED_16_CONNHDR2X6FSSMT_I1_3")
		)
		(pad "2" smd rect
			(at -0.5334 0 270)
			(size 0.7112 0.6096)
			(layers "B.Cu" "B.Mask" "B.Paste")
			(net "FPGA_IO_1")
		)
		(zone
			(layer "B.Cu")
			(hatch none 0.5)
			(connect_pads
				(clearance 0)
			)
			(min_thickness 0.25)
			(keepout
				(tracks allowed)
				(vias not_allowed)
				(pads allowed)
				(copperpour not_allowed)
				(footprints allowed)
			)
			(placement
				(enabled no)
				(sheetname "")
			)
			(fill
				(thermal_gap 0.5)
				(thermal_bridge_width 0.5)
				(island_removal_mode 0)
			)
			(polygon
				(pts
					(xy 152.1968 -42.1132) (xy 151.5872 -42.1132) (xy 151.5872 -41.9608) (xy 152.1968 -41.9608)
				)
			)
		)
		(zone
			(layer "B.Cu")
			(hatch none 0.5)
			(connect_pads
				(clearance 0)
			)
			(min_thickness 0.25)
			(keepout
				(tracks not_allowed)
				(vias allowed)
				(pads allowed)
				(copperpour not_allowed)
				(footprints allowed)
			)
			(placement
				(enabled no)
				(sheetname "")
			)
			(fill
				(thermal_gap 0.5)
				(thermal_bridge_width 0.5)
				(island_removal_mode 0)
			)
			(polygon
				(pts
					(xy 152.1968 -42.1132) (xy 151.5872 -42.1132) (xy 151.5872 -41.9608) (xy 152.1968 -41.9608)
				)
			)
		)
	)
)
